(kicad_pcb
	(version 20260206)
	(generator "pcbnew")
	(generator_version "10.0")
	(general
		(thickness 1.6)
		(legacy_teardrops no)
	)
	(paper "A4")
	(title_block
		(title "9054_F0T_PDB_BD_GPU_F_V04_1213_1550_OCP.brd")
		(comment 1 "Grand Teton / footprints 297-298 of 608")
	)
	(layers
		(0 "F.Cu" signal "TOP")
		(4 "In1.Cu" signal "GND")
		(6 "In2.Cu" signal "IN1")
		(8 "In3.Cu" signal "GND1")
		(10 "In4.Cu" signal "VCC")
		(12 "In5.Cu" signal "VCC1")
		(14 "In6.Cu" signal "GND2")
		(16 "In7.Cu" signal "IN2")
		(18 "In8.Cu" signal "GND3")
		(2 "B.Cu" signal "BOTTOM")
		(9 "F.Adhes" user "F.Adhesive")
		(11 "B.Adhes" user "B.Adhesive")
		(13 "F.Paste" user "Package Geometry/Pastemask Top")
		(15 "B.Paste" user "Package Geometry/Pastemask Bottom")
		(5 "F.SilkS" user "Ref Des/Silkscreen Top")
		(7 "B.SilkS" user "Ref Des/Silkscreen Bottom")
		(1 "F.Mask" user "Board Geometry/Soldermask Top")
		(3 "B.Mask" user "Board Geometry/Soldermask Bottom")
		(17 "Dwgs.User" user "User.Drawings")
		(19 "Cmts.User" user "User.Comments")
		(21 "Eco1.User" user "User.Eco1")
		(23 "Eco2.User" user "User.Eco2")
		(25 "Edge.Cuts" user "Board Geometry/Outline")
		(27 "Margin" user)
		(31 "F.CrtYd" user "Package Geometry/Place Bound Top")
		(29 "B.CrtYd" user "Package Geometry/Place Bound Bottom")
		(35 "F.Fab" user "Ref Des/Assembly Top")
		(33 "B.Fab" user "Ref Des/Assembly Bottom")
	)
	(footprint ""
		(layer "F.Cu")
		(at 398.375124 -168.82999)
		(property "Reference" "JP1"
			(at 3.960876 21.91766 0)
			(unlocked yes)
			(layer "F.SilkS")
			(effects
				(font
					(size 0.7874 0.5842)
					(thickness 0.1524)
				)
			)
		)
		(property "Value" ""
			(at 0 0 0)
			(layer "F.Fab")
			(effects
				(font
					(size 1.27 1.27)
				)
			)
		)
		(duplicate_pad_numbers_are_jumpers no)
		(fp_line
			(start -6.374892 -18.699988)
			(end 13.124942 -18.699988)
			(stroke
				(width 0.1524)
				(type default)
			)
			(layer "F.SilkS")
		)
		(fp_line
			(start -6.374892 20.999958)
			(end -6.374892 -18.699988)
			(stroke
				(width 0.1524)
				(type default)
			)
			(layer "F.SilkS")
		)
		(fp_line
			(start -3.374898 -15.699994)
			(end 10.124948 -15.699994)
			(stroke
				(width 0.1524)
				(type default)
			)
			(layer "F.SilkS")
		)
		(fp_line
			(start -3.374898 -6.500114)
			(end 10.124948 -6.500114)
			(stroke
				(width 0.1524)
				(type default)
			)
			(layer "F.SilkS")
		)
		(fp_line
			(start -3.374898 17.999964)
			(end -3.374898 -15.699994)
			(stroke
				(width 0.1524)
				(type default)
			)
			(layer "F.SilkS")
		)
		(fp_line
			(start 10.124948 -15.699994)
			(end 10.124948 17.999964)
			(stroke
				(width 0.1524)
				(type default)
			)
			(layer "F.SilkS")
		)
		(fp_line
			(start 10.124948 17.999964)
			(end -3.374898 17.999964)
			(stroke
				(width 0.1524)
				(type default)
			)
			(layer "F.SilkS")
		)
		(fp_line
			(start 13.124942 -18.699988)
			(end 13.124942 20.999958)
			(stroke
				(width 0.1524)
				(type default)
			)
			(layer "F.SilkS")
		)
		(fp_line
			(start 13.124942 20.999958)
			(end -6.374892 20.999958)
			(stroke
				(width 0.1524)
				(type default)
			)
			(layer "F.SilkS")
		)
		(fp_poly
			(pts
				(xy 0.451866 -2.025142) (xy -0.564134 -2.025142) (xy -0.056134 -1.009142)
			)
			(stroke
				(width 0)
				(type default)
			)
			(fill yes)
			(layer "F.SilkS")
		)
		(fp_line
			(start -6.374892 -18.699988)
			(end 13.124942 -18.699988)
			(stroke
				(width 0.1524)
				(type default)
			)
			(layer "B.SilkS")
		)
		(fp_line
			(start -6.374892 20.999958)
			(end -6.374892 -18.699988)
			(stroke
				(width 0.1524)
				(type default)
			)
			(layer "B.SilkS")
		)
		(fp_line
			(start 13.124942 -18.699988)
			(end 13.124942 20.999958)
			(stroke
				(width 0.1524)
				(type default)
			)
			(layer "B.SilkS")
		)
		(fp_line
			(start 13.124942 20.999958)
			(end -6.374892 20.999958)
			(stroke
				(width 0.1524)
				(type default)
			)
			(layer "B.SilkS")
		)
		(fp_line
			(start -6.374892 -18.699988)
			(end 13.124942 -18.699988)
			(stroke
				(width 0.1)
				(type default)
			)
			(layer "B.Fab")
		)
		(fp_line
			(start -6.374892 20.999958)
			(end -6.374892 -18.699988)
			(stroke
				(width 0.1)
				(type default)
			)
			(layer "B.Fab")
		)
		(fp_line
			(start 13.124942 -18.699988)
			(end 13.124942 20.999958)
			(stroke
				(width 0.1)
				(type default)
			)
			(layer "B.Fab")
		)
		(fp_line
			(start 13.124942 20.999958)
			(end -6.374892 20.999958)
			(stroke
				(width 0.1)
				(type default)
			)
			(layer "B.Fab")
		)
		(fp_line
			(start -3.374898 -15.699994)
			(end 10.124948 -15.699994)
			(stroke
				(width 0.1)
				(type default)
			)
			(layer "F.Fab")
		)
		(fp_line
			(start -3.374898 17.999964)
			(end -3.374898 -15.699994)
			(stroke
				(width 0.1)
				(type default)
			)
			(layer "F.Fab")
		)
		(fp_line
			(start 10.124948 -15.699994)
			(end 10.124948 17.999964)
			(stroke
				(width 0.1)
				(type default)
			)
			(layer "F.Fab")
		)
		(fp_line
			(start 10.124948 17.999964)
			(end -3.374898 17.999964)
			(stroke
				(width 0.1)
				(type default)
			)
			(layer "F.Fab")
		)
		(fp_poly
			(pts
				(xy -4.842256 -0.508) (xy -4.842256 0.508) (xy -3.826256 0)
			)
			(stroke
				(width 0)
				(type default)
			)
			(fill yes)
			(layer "F.Fab")
		)
		(fp_text user "PRESS-FIT"
			(at -0.865124 19.66849 0)
			(unlocked yes)
			(layer "F.SilkS")
			(effects
				(font
					(size 1.27 0.9652)
					(thickness 0.1524)
				)
				(justify left)
			)
		)
		(fp_text user "PRESS-FIT"
			(at 8.653526 16.68399 270)
			(unlocked yes)
			(layer "B.SilkS")
			(effects
				(font
					(size 1.905 1.4224)
					(thickness 0.1524)
				)
				(justify left mirror)
			)
		)
		(fp_text user "PRESS-FIT"
			(at 11.811 19.94535 0)
			(unlocked yes)
			(layer "B.Fab")
			(effects
				(font
					(size 1.905 1.4224)
					(thickness 0.1524)
				)
				(justify left mirror)
			)
		)
		(fp_text user "PRESS-FIT"
			(at -4.8768 19.94535 0)
			(unlocked yes)
			(layer "F.Fab")
			(effects
				(font
					(size 1.905 1.4224)
					(thickness 0.1524)
				)
				(justify left)
			)
		)
		(pad "P1_1" thru_hole rect
			(at 0 0)
			(size 1.156208 1.156208)
			(drill 0.749808)
			(layers "*.Cu" "*.Mask")
			(remove_unused_layers no)
			(net "P52V_HS1")
			(clearance 0.0508)
			(thermal_gap 0.0508)
			(padstack
				(mode front_inner_back)
				(layer "Inner"
					(shape circle)
					(size 1.156208 1.156208)
					(clearance 0.0508)
				)
				(layer "B.Cu"
					(shape rect)
					(size 1.156208 1.156208)
					(clearance 0.0508)
				)
			)
		)
		(pad "P1_2" thru_hole circle
			(at 0 1.999996)
			(size 1.156208 1.156208)
			(drill 0.749808)
			(layers "*.Cu" "*.Mask")
			(remove_unused_layers no)
			(net "P52V_HS1")
			(clearance 0.0508)
			(thermal_gap 0.0508)
		)
		(pad "P1_3" thru_hole circle
			(at 0 3.999992)
			(size 1.156208 1.156208)
			(drill 0.749808)
			(layers "*.Cu" "*.Mask")
			(remove_unused_layers no)
			(net "P52V_HS1")
			(clearance 0.0508)
			(thermal_gap 0.0508)
		)
		(pad "P1_4" thru_hole circle
			(at 0 5.999988)
			(size 1.156208 1.156208)
			(drill 0.749808)
			(layers "*.Cu" "*.Mask")
			(remove_unused_layers no)
			(net "P52V_HS1")
			(clearance 0.0508)
			(thermal_gap 0.0508)
		)
		(pad "P1_5" thru_hole circle
			(at 0 7.999984)
			(size 1.156208 1.156208)
			(drill 0.749808)
			(layers "*.Cu" "*.Mask")
			(remove_unused_layers no)
			(net "P52V_HS1")
			(clearance 0.0508)
			(thermal_gap 0.0508)
		)
		(pad "P1_6" thru_hole circle
			(at 0 9.99998)
			(size 1.156208 1.156208)
			(drill 0.749808)
			(layers "*.Cu" "*.Mask")
			(remove_unused_layers no)
			(net "P52V_HS1")
			(clearance 0.0508)
			(thermal_gap 0.0508)
		)
		(pad "P1_7" thru_hole circle
			(at 0 11.999976)
			(size 1.156208 1.156208)
			(drill 0.749808)
			(layers "*.Cu" "*.Mask")
			(remove_unused_layers no)
			(net "P52V_HS1")
			(clearance 0.0508)
			(thermal_gap 0.0508)
		)
		(pad "P1_8" thru_hole circle
			(at 0 13.999972)
			(size 1.156208 1.156208)
			(drill 0.749808)
			(layers "*.Cu" "*.Mask")
			(remove_unused_layers no)
			(net "P52V_HS1")
			(clearance 0.0508)
			(thermal_gap 0.0508)
		)
		(pad "P1_9" thru_hole circle
			(at 0 15.999968)
			(size 1.156208 1.156208)
			(drill 0.749808)
			(layers "*.Cu" "*.Mask")
			(remove_unused_layers no)
			(net "P52V_HS1")
			(clearance 0.0508)
			(thermal_gap 0.0508)
		)
		(pad "P1_10" thru_hole circle
			(at 1.999996 0)
			(size 1.156208 1.156208)
			(drill 0.749808)
			(layers "*.Cu" "*.Mask")
			(remove_unused_layers no)
			(net "P52V_HS1")
			(clearance 0.0508)
			(thermal_gap 0.0508)
		)
		(pad "P1_11" thru_hole circle
			(at 1.999996 1.999996)
			(size 1.156208 1.156208)
			(drill 0.749808)
			(layers "*.Cu" "*.Mask")
			(remove_unused_layers no)
			(net "P52V_HS1")
			(clearance 0.0508)
			(thermal_gap 0.0508)
		)
		(pad "P1_12" thru_hole circle
			(at 1.999996 3.999992)
			(size 1.156208 1.156208)
			(drill 0.749808)
			(layers "*.Cu" "*.Mask")
			(remove_unused_layers no)
			(net "P52V_HS1")
			(clearance 0.0508)
			(thermal_gap 0.0508)
		)
		(pad "P1_13" thru_hole circle
			(at 1.999996 5.999988)
			(size 1.156208 1.156208)
			(drill 0.749808)
			(layers "*.Cu" "*.Mask")
			(remove_unused_layers no)
			(net "P52V_HS1")
			(clearance 0.0508)
			(thermal_gap 0.0508)
		)
		(pad "P1_14" thru_hole circle
			(at 1.999996 7.999984)
			(size 1.156208 1.156208)
			(drill 0.749808)
			(layers "*.Cu" "*.Mask")
			(remove_unused_layers no)
			(net "P52V_HS1")
			(clearance 0.0508)
			(thermal_gap 0.0508)
		)
		(pad "P1_15" thru_hole circle
			(at 1.999996 9.99998)
			(size 1.156208 1.156208)
			(drill 0.749808)
			(layers "*.Cu" "*.Mask")
			(remove_unused_layers no)
			(net "P52V_HS1")
			(clearance 0.0508)
			(thermal_gap 0.0508)
		)
		(pad "P1_16" thru_hole circle
			(at 1.999996 11.999976)
			(size 1.156208 1.156208)
			(drill 0.749808)
			(layers "*.Cu" "*.Mask")
			(remove_unused_layers no)
			(net "P52V_HS1")
			(clearance 0.0508)
			(thermal_gap 0.0508)
		)
		(pad "P1_17" thru_hole circle
			(at 1.999996 13.999972)
			(size 1.156208 1.156208)
			(drill 0.749808)
			(layers "*.Cu" "*.Mask")
			(remove_unused_layers no)
			(net "P52V_HS1")
			(clearance 0.0508)
			(thermal_gap 0.0508)
		)
		(pad "P1_18" thru_hole circle
			(at 1.999996 15.999968)
			(size 1.156208 1.156208)
			(drill 0.749808)
			(layers "*.Cu" "*.Mask")
			(remove_unused_layers no)
			(net "P52V_HS1")
			(clearance 0.0508)
			(thermal_gap 0.0508)
		)
		(pad "P2_1" thru_hole circle
			(at 4.750054 0)
			(size 1.156208 1.156208)
			(drill 0.749808)
			(layers "*.Cu" "*.Mask")
			(remove_unused_layers no)
			(net "GND")
			(clearance 0.0508)
			(thermal_gap 0.0508)
		)
		(pad "P2_2" thru_hole circle
			(at 4.750054 1.999996)
			(size 1.156208 1.156208)
			(drill 0.749808)
			(layers "*.Cu" "*.Mask")
			(remove_unused_layers no)
			(net "GND")
			(clearance 0.0508)
			(thermal_gap 0.0508)
		)
		(pad "P2_3" thru_hole circle
			(at 4.750054 3.999992)
			(size 1.156208 1.156208)
			(drill 0.749808)
			(layers "*.Cu" "*.Mask")
			(remove_unused_layers no)
			(net "GND")
			(clearance 0.0508)
			(thermal_gap 0.0508)
		)
		(pad "P2_4" thru_hole circle
			(at 4.750054 5.999988)
			(size 1.156208 1.156208)
			(drill 0.749808)
			(layers "*.Cu" "*.Mask")
			(remove_unused_layers no)
			(net "GND")
			(clearance 0.0508)
			(thermal_gap 0.0508)
		)
		(pad "P2_5" thru_hole circle
			(at 4.750054 7.999984)
			(size 1.156208 1.156208)
			(drill 0.749808)
			(layers "*.Cu" "*.Mask")
			(remove_unused_layers no)
			(net "GND")
			(clearance 0.0508)
			(thermal_gap 0.0508)
		)
		(pad "P2_6" thru_hole circle
			(at 4.750054 9.99998)
			(size 1.156208 1.156208)
			(drill 0.749808)
			(layers "*.Cu" "*.Mask")
			(remove_unused_layers no)
			(net "GND")
			(clearance 0.0508)
			(thermal_gap 0.0508)
		)
		(pad "P2_7" thru_hole circle
			(at 4.750054 11.999976)
			(size 1.156208 1.156208)
			(drill 0.749808)
			(layers "*.Cu" "*.Mask")
			(remove_unused_layers no)
			(net "GND")
			(clearance 0.0508)
			(thermal_gap 0.0508)
		)
		(pad "P2_8" thru_hole circle
			(at 4.750054 13.999972)
			(size 1.156208 1.156208)
			(drill 0.749808)
			(layers "*.Cu" "*.Mask")
			(remove_unused_layers no)
			(net "GND")
			(clearance 0.0508)
			(thermal_gap 0.0508)
		)
		(pad "P2_9" thru_hole circle
			(at 4.750054 15.999968)
			(size 1.156208 1.156208)
			(drill 0.749808)
			(layers "*.Cu" "*.Mask")
			(remove_unused_layers no)
			(net "GND")
			(clearance 0.0508)
			(thermal_gap 0.0508)
		)
		(pad "P2_10" thru_hole circle
			(at 6.75005 0)
			(size 1.156208 1.156208)
			(drill 0.749808)
			(layers "*.Cu" "*.Mask")
			(remove_unused_layers no)
			(net "GND")
			(clearance 0.0508)
			(thermal_gap 0.0508)
		)
		(pad "P2_11" thru_hole circle
			(at 6.75005 1.999996)
			(size 1.156208 1.156208)
			(drill 0.749808)
			(layers "*.Cu" "*.Mask")
			(remove_unused_layers no)
			(net "GND")
			(clearance 0.0508)
			(thermal_gap 0.0508)
		)
		(pad "P2_12" thru_hole circle
			(at 6.75005 3.999992)
			(size 1.156208 1.156208)
			(drill 0.749808)
			(layers "*.Cu" "*.Mask")
			(remove_unused_layers no)
			(net "GND")
			(clearance 0.0508)
			(thermal_gap 0.0508)
		)
		(pad "P2_13" thru_hole circle
			(at 6.75005 5.999988)
			(size 1.156208 1.156208)
			(drill 0.749808)
			(layers "*.Cu" "*.Mask")
			(remove_unused_layers no)
			(net "GND")
			(clearance 0.0508)
			(thermal_gap 0.0508)
		)
		(pad "P2_14" thru_hole circle
			(at 6.75005 7.999984)
			(size 1.156208 1.156208)
			(drill 0.749808)
			(layers "*.Cu" "*.Mask")
			(remove_unused_layers no)
			(net "GND")
			(clearance 0.0508)
			(thermal_gap 0.0508)
		)
		(pad "P2_15" thru_hole circle
			(at 6.75005 9.99998)
			(size 1.156208 1.156208)
			(drill 0.749808)
			(layers "*.Cu" "*.Mask")
			(remove_unused_layers no)
			(net "GND")
			(clearance 0.0508)
			(thermal_gap 0.0508)
		)
		(pad "P2_16" thru_hole circle
			(at 6.75005 11.999976)
			(size 1.156208 1.156208)
			(drill 0.749808)
			(layers "*.Cu" "*.Mask")
			(remove_unused_layers no)
			(net "GND")
			(clearance 0.0508)
			(thermal_gap 0.0508)
		)
		(pad "P2_17" thru_hole circle
			(at 6.75005 13.999972)
			(size 1.156208 1.156208)
			(drill 0.749808)
			(layers "*.Cu" "*.Mask")
			(remove_unused_layers no)
			(net "GND")
			(clearance 0.0508)
			(thermal_gap 0.0508)
		)
		(pad "P2_18" thru_hole circle
			(at 6.75005 15.999968)
			(size 1.156208 1.156208)
			(drill 0.749808)
			(layers "*.Cu" "*.Mask")
			(remove_unused_layers no)
			(net "GND")
			(clearance 0.0508)
			(thermal_gap 0.0508)
		)
		(zone
			(layer "B.Cu")
			(hatch none 0.5)
			(connect_pads
				(clearance 0)
			)
			(min_thickness 0.25)
			(keepout
				(tracks allowed)
				(vias not_allowed)
				(pads allowed)
				(copperpour not_allowed)
				(footprints allowed)
			)
			(placement
				(enabled no)
				(sheetname "")
			)
			(fill
				(thermal_gap 0.5)
				(thermal_bridge_width 0.5)
				(island_removal_mode 0)
			)
			(polygon
				(pts
					(xy 397.73352 -169.471594) (xy 397.73352 -152.188418) (xy 405.766778 -152.188418) (xy 405.766778 -169.471594)
				)
			)
		)
	)
	(footprint ""
		(layer "F.Cu")
		(at 470.449656 -107.502452 90)
		(property "Reference" "R87"
			(at 0 0 90)
			(layer "F.SilkS")
			(hide yes)
			(effects
				(font
					(size 1.27 1.27)
				)
			)
		)
		(property "Value" ""
			(at 0 0 90)
			(layer "F.Fab")
			(effects
				(font
					(size 1.27 1.27)
				)
			)
		)
		(duplicate_pad_numbers_are_jumpers no)
		(fp_line
			(start 0.7874 -0.4064)
			(end 0.7874 0.4064)
			(stroke
				(width 0.1524)
				(type default)
			)
			(layer "F.SilkS")
		)
		(fp_line
			(start -0.7874 -0.4064)
			(end 0.7874 -0.4064)
			(stroke
				(width 0.1524)
				(type default)
			)
			(layer "F.SilkS")
		)
		(fp_line
			(start 0.7874 0.4064)
			(end -0.7874 0.4064)
			(stroke
				(width 0.1524)
				(type default)
			)
			(layer "F.SilkS")
		)
		(fp_line
			(start -0.7874 0.4064)
			(end -0.7874 -0.4064)
			(stroke
				(width 0.1524)
				(type default)
			)
			(layer "F.SilkS")
		)
		(fp_line
			(start -0.12065 -0.305054)
			(end -0.12065 -0.2794)
			(stroke
				(width 0.1)
				(type default)
			)
			(layer "F.Fab")
		)
		(fp_line
			(start -0.67945 -0.305054)
			(end -0.12065 -0.305054)
			(stroke
				(width 0.1)
				(type default)
			)
			(layer "F.Fab")
		)
		(fp_line
			(start 0.67945 -0.3048)
			(end 0.67945 0.3048)
			(stroke
				(width 0.1)
				(type default)
			)
			(layer "F.Fab")
		)
		(fp_line
			(start 0.12065 -0.3048)
			(end 0.67945 -0.3048)
			(stroke
				(width 0.1)
				(type default)
			)
			(layer "F.Fab")
		)
		(fp_line
			(start 0.12065 -0.2794)
			(end 0.12065 -0.3048)
			(stroke
				(width 0.1)
				(type default)
			)
			(layer "F.Fab")
		)
		(fp_line
			(start -0.12065 -0.2794)
			(end 0.12065 -0.2794)
			(stroke
				(width 0.1)
				(type default)
			)
			(layer "F.Fab")
		)
		(fp_line
			(start 0.120396 0.2794)
			(end -0.12065 0.2794)
			(stroke
				(width 0.1)
				(type default)
			)
			(layer "F.Fab")
		)
		(fp_line
			(start -0.12065 0.2794)
			(end -0.12065 0.3048)
			(stroke
				(width 0.1)
				(type default)
			)
			(layer "F.Fab")
		)
		(fp_line
			(start 0.67945 0.3048)
			(end 0.120396 0.3048)
			(stroke
				(width 0.1)
				(type default)
			)
			(layer "F.Fab")
		)
		(fp_line
			(start 0.120396 0.3048)
			(end 0.120396 0.2794)
			(stroke
				(width 0.1)
				(type default)
			)
			(layer "F.Fab")
		)
		(fp_line
			(start -0.12065 0.3048)
			(end -0.67945 0.3048)
			(stroke
				(width 0.1)
				(type default)
			)
			(layer "F.Fab")
		)
		(fp_line
			(start -0.67945 0.3048)
			(end -0.67945 -0.305054)
			(stroke
				(width 0.1)
				(type default)
			)
			(layer "F.Fab")
		)
		(pad "1" smd circle
			(at -0.40005 0 90)
			(size 0 0)
			(layers "F.Cu" "F.Mask" "F.Paste")
			(net "SMB_P52V_SDA")
		)
		(pad "2" smd circle
			(at 0.40005 0 90)
			(size 0 0)
			(layers "F.Cu" "F.Mask" "F.Paste")
			(net "SMB_P52V_R_SDA")
		)
	)
)
